(kicad_pcb
	(version 20260206)
	(generator "pcbnew")
	(generator_version "10.0")
	(general
		(thickness 1.6)
		(legacy_teardrops no)
	)
	(paper "A4")
	(title_block
		(title "04192023_DAF0TMB3IC0_F0TG_MB_C_brd_V02_OCP.brd")
		(comment 1 "Grand Teton / footprints 1730-1736 of 8354")
	)
	(layers
		(0 "F.Cu" signal "TOP")
		(4 "In1.Cu" signal "GND")
		(6 "In2.Cu" signal "IN1")
		(8 "In3.Cu" signal "GND1")
		(10 "In4.Cu" signal "IN2")
		(12 "In5.Cu" signal "GND2")
		(14 "In6.Cu" signal "IN3")
		(16 "In7.Cu" signal "GND3")
		(18 "In8.Cu" signal "VCC")
		(20 "In9.Cu" signal "VCC1")
		(22 "In10.Cu" signal "GND4")
		(24 "In11.Cu" signal "IN4")
		(26 "In12.Cu" signal "GND5")
		(28 "In13.Cu" signal "IN5")
		(30 "In14.Cu" signal "GND6")
		(32 "In15.Cu" signal "IN6")
		(34 "In16.Cu" signal "GND7")
		(2 "B.Cu" signal "BOTTOM")
		(9 "F.Adhes" user "F.Adhesive")
		(11 "B.Adhes" user "B.Adhesive")
		(13 "F.Paste" user "Package Geometry/Pastemask Top")
		(15 "B.Paste" user "Package Geometry/Pastemask Bottom")
		(5 "F.SilkS" user "Ref Des/Silkscreen Top")
		(7 "B.SilkS" user "Ref Des/Silkscreen Bottom")
		(1 "F.Mask" user "Board Geometry/Soldermask Top")
		(3 "B.Mask" user "Board Geometry/Soldermask Bottom")
		(17 "Dwgs.User" user "User.Drawings")
		(19 "Cmts.User" user "User.Comments")
		(21 "Eco1.User" user "User.Eco1")
		(23 "Eco2.User" user "User.Eco2")
		(25 "Edge.Cuts" user "Board Geometry/Outline")
		(27 "Margin" user)
		(31 "F.CrtYd" user "Package Geometry/Place Bound Top")
		(29 "B.CrtYd" user "Package Geometry/Place Bound Bottom")
		(35 "F.Fab" user "Ref Des/Assembly Top")
		(33 "B.Fab" user "Ref Des/Assembly Bottom")
	)
	(footprint ""
		(layer "F.Cu")
		(at 175.641 -100.294948 -90)
		(property "Reference" "R163"
			(at 0 0 270)
			(layer "F.SilkS")
			(hide yes)
			(effects
				(font
					(size 1.27 1.27)
				)
			)
		)
		(property "Value" ""
			(at 0 0 270)
			(layer "F.Fab")
			(effects
				(font
					(size 1.27 1.27)
				)
			)
		)
		(duplicate_pad_numbers_are_jumpers no)
		(fp_line
			(start -0.7874 0.4064)
			(end -0.7874 -0.4064)
			(stroke
				(width 0.1524)
				(type default)
			)
			(layer "F.SilkS")
		)
		(fp_line
			(start 0.7874 0.4064)
			(end -0.7874 0.4064)
			(stroke
				(width 0.1524)
				(type default)
			)
			(layer "F.SilkS")
		)
		(fp_line
			(start -0.7874 -0.4064)
			(end 0.7874 -0.4064)
			(stroke
				(width 0.1524)
				(type default)
			)
			(layer "F.SilkS")
		)
		(fp_line
			(start 0.7874 -0.4064)
			(end 0.7874 0.4064)
			(stroke
				(width 0.1524)
				(type default)
			)
			(layer "F.SilkS")
		)
		(fp_line
			(start -0.67945 0.3048)
			(end -0.67945 -0.305054)
			(stroke
				(width 0.1)
				(type default)
			)
			(layer "F.Fab")
		)
		(fp_line
			(start -0.12065 0.3048)
			(end -0.67945 0.3048)
			(stroke
				(width 0.1)
				(type default)
			)
			(layer "F.Fab")
		)
		(fp_line
			(start 0.120396 0.3048)
			(end 0.120396 0.2794)
			(stroke
				(width 0.1)
				(type default)
			)
			(layer "F.Fab")
		)
		(fp_line
			(start 0.67945 0.3048)
			(end 0.120396 0.3048)
			(stroke
				(width 0.1)
				(type default)
			)
			(layer "F.Fab")
		)
		(fp_line
			(start -0.12065 0.2794)
			(end -0.12065 0.3048)
			(stroke
				(width 0.1)
				(type default)
			)
			(layer "F.Fab")
		)
		(fp_line
			(start 0.120396 0.2794)
			(end -0.12065 0.2794)
			(stroke
				(width 0.1)
				(type default)
			)
			(layer "F.Fab")
		)
		(fp_line
			(start -0.12065 -0.2794)
			(end 0.12065 -0.2794)
			(stroke
				(width 0.1)
				(type default)
			)
			(layer "F.Fab")
		)
		(fp_line
			(start 0.12065 -0.2794)
			(end 0.12065 -0.3048)
			(stroke
				(width 0.1)
				(type default)
			)
			(layer "F.Fab")
		)
		(fp_line
			(start 0.12065 -0.3048)
			(end 0.67945 -0.3048)
			(stroke
				(width 0.1)
				(type default)
			)
			(layer "F.Fab")
		)
		(fp_line
			(start 0.67945 -0.3048)
			(end 0.67945 0.3048)
			(stroke
				(width 0.1)
				(type default)
			)
			(layer "F.Fab")
		)
		(fp_line
			(start -0.67945 -0.305054)
			(end -0.12065 -0.305054)
			(stroke
				(width 0.1)
				(type default)
			)
			(layer "F.Fab")
		)
		(fp_line
			(start -0.12065 -0.305054)
			(end -0.12065 -0.2794)
			(stroke
				(width 0.1)
				(type default)
			)
			(layer "F.Fab")
		)
		(pad "1" smd circle
			(at -0.40005 0 270)
			(size 0 0)
			(layers "F.Cu" "F.Mask" "F.Paste")
			(net "FM_I3C_CPU0_MUX0_OE_R_N")
		)
		(pad "2" smd circle
			(at 0.40005 0 270)
			(size 0 0)
			(layers "F.Cu" "F.Mask" "F.Paste")
			(net "FM_I3C_CPU0_MUX0_OE_N")
		)
	)
	(footprint ""
		(layer "F.Cu")
		(at 419.950138 -348.110556 180)
		(property "Reference" "PC169"
			(at 0 0 180)
			(layer "F.SilkS")
			(hide yes)
			(effects
				(font
					(size 1.27 1.27)
				)
			)
		)
		(property "Value" ""
			(at 0 0 180)
			(layer "F.Fab")
			(effects
				(font
					(size 1.27 1.27)
				)
			)
		)
		(duplicate_pad_numbers_are_jumpers no)
		(fp_line
			(start 0.7874 0.4064)
			(end -0.7874 0.4064)
			(stroke
				(width 0.1524)
				(type default)
			)
			(layer "F.SilkS")
		)
		(fp_line
			(start 0.7874 -0.4064)
			(end 0.7874 0.4064)
			(stroke
				(width 0.1524)
				(type default)
			)
			(layer "F.SilkS")
		)
		(fp_line
			(start -0.7874 0.4064)
			(end -0.7874 -0.4064)
			(stroke
				(width 0.1524)
				(type default)
			)
			(layer "F.SilkS")
		)
		(fp_line
			(start -0.7874 -0.4064)
			(end 0.7874 -0.4064)
			(stroke
				(width 0.1524)
				(type default)
			)
			(layer "F.SilkS")
		)
		(fp_line
			(start 0.67945 0.3048)
			(end 0.120396 0.3048)
			(stroke
				(width 0.1)
				(type default)
			)
			(layer "F.Fab")
		)
		(fp_line
			(start 0.67945 -0.3048)
			(end 0.67945 0.3048)
			(stroke
				(width 0.1)
				(type default)
			)
			(layer "F.Fab")
		)
		(fp_line
			(start 0.12065 -0.2794)
			(end 0.12065 -0.3048)
			(stroke
				(width 0.1)
				(type default)
			)
			(layer "F.Fab")
		)
		(fp_line
			(start 0.12065 -0.3048)
			(end 0.67945 -0.3048)
			(stroke
				(width 0.1)
				(type default)
			)
			(layer "F.Fab")
		)
		(fp_line
			(start 0.120396 0.3048)
			(end 0.120396 0.2794)
			(stroke
				(width 0.1)
				(type default)
			)
			(layer "F.Fab")
		)
		(fp_line
			(start 0.120396 0.2794)
			(end -0.12065 0.2794)
			(stroke
				(width 0.1)
				(type default)
			)
			(layer "F.Fab")
		)
		(fp_line
			(start -0.12065 0.3048)
			(end -0.67945 0.3048)
			(stroke
				(width 0.1)
				(type default)
			)
			(layer "F.Fab")
		)
		(fp_line
			(start -0.12065 0.2794)
			(end -0.12065 0.3048)
			(stroke
				(width 0.1)
				(type default)
			)
			(layer "F.Fab")
		)
		(fp_line
			(start -0.12065 -0.2794)
			(end 0.12065 -0.2794)
			(stroke
				(width 0.1)
				(type default)
			)
			(layer "F.Fab")
		)
		(fp_line
			(start -0.12065 -0.305054)
			(end -0.12065 -0.2794)
			(stroke
				(width 0.1)
				(type default)
			)
			(layer "F.Fab")
		)
		(fp_line
			(start -0.67945 0.3048)
			(end -0.67945 -0.305054)
			(stroke
				(width 0.1)
				(type default)
			)
			(layer "F.Fab")
		)
		(fp_line
			(start -0.67945 -0.305054)
			(end -0.12065 -0.305054)
			(stroke
				(width 0.1)
				(type default)
			)
			(layer "F.Fab")
		)
		(pad "1" smd circle
			(at -0.40005 0 180)
			(size 0 0)
			(layers "F.Cu" "F.Mask" "F.Paste")
			(net "SW_PVDD11_S3_P0_SW1")
		)
		(pad "2" smd circle
			(at 0.40005 0 180)
			(size 0 0)
			(layers "F.Cu" "F.Mask" "F.Paste")
			(net "SW_PVDD11_S3_P0_SW1_RC")
		)
	)
	(footprint ""
		(layer "F.Cu")
		(at 167.894 -99.06 180)
		(property "Reference" "R1143"
			(at 0 0 180)
			(layer "F.SilkS")
			(hide yes)
			(effects
				(font
					(size 1.27 1.27)
				)
			)
		)
		(property "Value" ""
			(at 0 0 180)
			(layer "F.Fab")
			(effects
				(font
					(size 1.27 1.27)
				)
			)
		)
		(duplicate_pad_numbers_are_jumpers no)
		(fp_line
			(start 0.7874 0.4064)
			(end -0.7874 0.4064)
			(stroke
				(width 0.1524)
				(type default)
			)
			(layer "F.SilkS")
		)
		(fp_line
			(start 0.7874 -0.4064)
			(end 0.7874 0.4064)
			(stroke
				(width 0.1524)
				(type default)
			)
			(layer "F.SilkS")
		)
		(fp_line
			(start -0.7874 0.4064)
			(end -0.7874 -0.4064)
			(stroke
				(width 0.1524)
				(type default)
			)
			(layer "F.SilkS")
		)
		(fp_line
			(start -0.7874 -0.4064)
			(end 0.7874 -0.4064)
			(stroke
				(width 0.1524)
				(type default)
			)
			(layer "F.SilkS")
		)
		(fp_line
			(start 0.67945 0.3048)
			(end 0.120396 0.3048)
			(stroke
				(width 0.1)
				(type default)
			)
			(layer "F.Fab")
		)
		(fp_line
			(start 0.67945 -0.3048)
			(end 0.67945 0.3048)
			(stroke
				(width 0.1)
				(type default)
			)
			(layer "F.Fab")
		)
		(fp_line
			(start 0.12065 -0.2794)
			(end 0.12065 -0.3048)
			(stroke
				(width 0.1)
				(type default)
			)
			(layer "F.Fab")
		)
		(fp_line
			(start 0.12065 -0.3048)
			(end 0.67945 -0.3048)
			(stroke
				(width 0.1)
				(type default)
			)
			(layer "F.Fab")
		)
		(fp_line
			(start 0.120396 0.3048)
			(end 0.120396 0.2794)
			(stroke
				(width 0.1)
				(type default)
			)
			(layer "F.Fab")
		)
		(fp_line
			(start 0.120396 0.2794)
			(end -0.12065 0.2794)
			(stroke
				(width 0.1)
				(type default)
			)
			(layer "F.Fab")
		)
		(fp_line
			(start -0.12065 0.3048)
			(end -0.67945 0.3048)
			(stroke
				(width 0.1)
				(type default)
			)
			(layer "F.Fab")
		)
		(fp_line
			(start -0.12065 0.2794)
			(end -0.12065 0.3048)
			(stroke
				(width 0.1)
				(type default)
			)
			(layer "F.Fab")
		)
		(fp_line
			(start -0.12065 -0.2794)
			(end 0.12065 -0.2794)
			(stroke
				(width 0.1)
				(type default)
			)
			(layer "F.Fab")
		)
		(fp_line
			(start -0.12065 -0.305054)
			(end -0.12065 -0.2794)
			(stroke
				(width 0.1)
				(type default)
			)
			(layer "F.Fab")
		)
		(fp_line
			(start -0.67945 0.3048)
			(end -0.67945 -0.305054)
			(stroke
				(width 0.1)
				(type default)
			)
			(layer "F.Fab")
		)
		(fp_line
			(start -0.67945 -0.305054)
			(end -0.12065 -0.305054)
			(stroke
				(width 0.1)
				(type default)
			)
			(layer "F.Fab")
		)
		(pad "1" smd circle
			(at -0.40005 0 180)
			(size 0 0)
			(layers "F.Cu" "F.Mask" "F.Paste")
			(net "OCP_V3_1_P3V3_PLD_PWRGD")
		)
		(pad "2" smd circle
			(at 0.40005 0 180)
			(size 0 0)
			(layers "F.Cu" "F.Mask" "F.Paste")
			(net "OCP_V3_1_P3V3_PLD_R_PWRGD")
		)
	)
	(footprint ""
		(layer "F.Cu")
		(at 361.046014 -257.744976)
		(property "Reference" "C2573"
			(at 0 0 0)
			(layer "F.SilkS")
			(hide yes)
			(effects
				(font
					(size 1.27 1.27)
				)
			)
		)
		(property "Value" ""
			(at 0 0 0)
			(layer "F.Fab")
			(effects
				(font
					(size 1.27 1.27)
				)
			)
		)
		(duplicate_pad_numbers_are_jumpers no)
		(fp_line
			(start -0.7874 -0.4064)
			(end 0.7874 -0.4064)
			(stroke
				(width 0.1524)
				(type default)
			)
			(layer "F.SilkS")
		)
		(fp_line
			(start -0.7874 0.4064)
			(end -0.7874 -0.4064)
			(stroke
				(width 0.1524)
				(type default)
			)
			(layer "F.SilkS")
		)
		(fp_line
			(start 0.7874 -0.4064)
			(end 0.7874 0.4064)
			(stroke
				(width 0.1524)
				(type default)
			)
			(layer "F.SilkS")
		)
		(fp_line
			(start 0.7874 0.4064)
			(end -0.7874 0.4064)
			(stroke
				(width 0.1524)
				(type default)
			)
			(layer "F.SilkS")
		)
		(fp_line
			(start -0.67945 -0.305054)
			(end -0.12065 -0.305054)
			(stroke
				(width 0.1)
				(type default)
			)
			(layer "F.Fab")
		)
		(fp_line
			(start -0.67945 0.3048)
			(end -0.67945 -0.305054)
			(stroke
				(width 0.1)
				(type default)
			)
			(layer "F.Fab")
		)
		(fp_line
			(start -0.12065 -0.305054)
			(end -0.12065 -0.2794)
			(stroke
				(width 0.1)
				(type default)
			)
			(layer "F.Fab")
		)
		(fp_line
			(start -0.12065 -0.2794)
			(end 0.12065 -0.2794)
			(stroke
				(width 0.1)
				(type default)
			)
			(layer "F.Fab")
		)
		(fp_line
			(start -0.12065 0.2794)
			(end -0.12065 0.3048)
			(stroke
				(width 0.1)
				(type default)
			)
			(layer "F.Fab")
		)
		(fp_line
			(start -0.12065 0.3048)
			(end -0.67945 0.3048)
			(stroke
				(width 0.1)
				(type default)
			)
			(layer "F.Fab")
		)
		(fp_line
			(start 0.120396 0.2794)
			(end -0.12065 0.2794)
			(stroke
				(width 0.1)
				(type default)
			)
			(layer "F.Fab")
		)
		(fp_line
			(start 0.120396 0.3048)
			(end 0.120396 0.2794)
			(stroke
				(width 0.1)
				(type default)
			)
			(layer "F.Fab")
		)
		(fp_line
			(start 0.12065 -0.3048)
			(end 0.67945 -0.3048)
			(stroke
				(width 0.1)
				(type default)
			)
			(layer "F.Fab")
		)
		(fp_line
			(start 0.12065 -0.2794)
			(end 0.12065 -0.3048)
			(stroke
				(width 0.1)
				(type default)
			)
			(layer "F.Fab")
		)
		(fp_line
			(start 0.67945 -0.3048)
			(end 0.67945 0.3048)
			(stroke
				(width 0.1)
				(type default)
			)
			(layer "F.Fab")
		)
		(fp_line
			(start 0.67945 0.3048)
			(end 0.120396 0.3048)
			(stroke
				(width 0.1)
				(type default)
			)
			(layer "F.Fab")
		)
		(pad "1" smd circle
			(at -0.40005 0)
			(size 0 0)
			(layers "F.Cu" "F.Mask" "F.Paste")
			(net "PVDDCR_SOC_P0")
		)
		(pad "2" smd circle
			(at 0.40005 0)
			(size 0 0)
			(layers "F.Cu" "F.Mask" "F.Paste")
			(net "GND")
		)
	)
	(footprint ""
		(layer "F.Cu")
		(at 149.401276 -44.8437 90)
		(property "Reference" "C1323"
			(at 0 0 90)
			(layer "F.SilkS")
			(hide yes)
			(effects
				(font
					(size 1.27 1.27)
				)
			)
		)
		(property "Value" ""
			(at 0 0 90)
			(layer "F.Fab")
			(effects
				(font
					(size 1.27 1.27)
				)
			)
		)
		(duplicate_pad_numbers_are_jumpers no)
		(fp_line
			(start 0.7874 -0.4064)
			(end 0.7874 0.4064)
			(stroke
				(width 0.1524)
				(type default)
			)
			(layer "F.SilkS")
		)
		(fp_line
			(start -0.7874 -0.4064)
			(end 0.7874 -0.4064)
			(stroke
				(width 0.1524)
				(type default)
			)
			(layer "F.SilkS")
		)
		(fp_line
			(start 0.7874 0.4064)
			(end -0.7874 0.4064)
			(stroke
				(width 0.1524)
				(type default)
			)
			(layer "F.SilkS")
		)
		(fp_line
			(start -0.7874 0.4064)
			(end -0.7874 -0.4064)
			(stroke
				(width 0.1524)
				(type default)
			)
			(layer "F.SilkS")
		)
		(fp_line
			(start -0.12065 -0.305054)
			(end -0.12065 -0.2794)
			(stroke
				(width 0.1)
				(type default)
			)
			(layer "F.Fab")
		)
		(fp_line
			(start -0.67945 -0.305054)
			(end -0.12065 -0.305054)
			(stroke
				(width 0.1)
				(type default)
			)
			(layer "F.Fab")
		)
		(fp_line
			(start 0.67945 -0.3048)
			(end 0.67945 0.3048)
			(stroke
				(width 0.1)
				(type default)
			)
			(layer "F.Fab")
		)
		(fp_line
			(start 0.12065 -0.3048)
			(end 0.67945 -0.3048)
			(stroke
				(width 0.1)
				(type default)
			)
			(layer "F.Fab")
		)
		(fp_line
			(start 0.12065 -0.2794)
			(end 0.12065 -0.3048)
			(stroke
				(width 0.1)
				(type default)
			)
			(layer "F.Fab")
		)
		(fp_line
			(start -0.12065 -0.2794)
			(end 0.12065 -0.2794)
			(stroke
				(width 0.1)
				(type default)
			)
			(layer "F.Fab")
		)
		(fp_line
			(start 0.120396 0.2794)
			(end -0.12065 0.2794)
			(stroke
				(width 0.1)
				(type default)
			)
			(layer "F.Fab")
		)
		(fp_line
			(start -0.12065 0.2794)
			(end -0.12065 0.3048)
			(stroke
				(width 0.1)
				(type default)
			)
			(layer "F.Fab")
		)
		(fp_line
			(start 0.67945 0.3048)
			(end 0.120396 0.3048)
			(stroke
				(width 0.1)
				(type default)
			)
			(layer "F.Fab")
		)
		(fp_line
			(start 0.120396 0.3048)
			(end 0.120396 0.2794)
			(stroke
				(width 0.1)
				(type default)
			)
			(layer "F.Fab")
		)
		(fp_line
			(start -0.12065 0.3048)
			(end -0.67945 0.3048)
			(stroke
				(width 0.1)
				(type default)
			)
			(layer "F.Fab")
		)
		(fp_line
			(start -0.67945 0.3048)
			(end -0.67945 -0.305054)
			(stroke
				(width 0.1)
				(type default)
			)
			(layer "F.Fab")
		)
		(pad "1" smd circle
			(at -0.40005 0 90)
			(size 0 0)
			(layers "F.Cu" "F.Mask" "F.Paste")
			(net "P1V8_AUX")
		)
		(pad "2" smd circle
			(at 0.40005 0 90)
			(size 0 0)
			(layers "F.Cu" "F.Mask" "F.Paste")
			(net "GND")
		)
	)
	(footprint ""
		(layer "F.Cu")
		(at 77.219302 -370.57203 -90)
		(property "Reference" "C735"
			(at 0 0 270)
			(layer "F.SilkS")
			(hide yes)
			(effects
				(font
					(size 1.27 1.27)
				)
			)
		)
		(property "Value" ""
			(at 0 0 270)
			(layer "F.Fab")
			(effects
				(font
					(size 1.27 1.27)
				)
			)
		)
		(duplicate_pad_numbers_are_jumpers no)
		(fp_line
			(start -0.299974 0.150114)
			(end -0.299974 -0.150114)
			(stroke
				(width 0.1)
				(type default)
			)
			(layer "F.Fab")
		)
		(fp_line
			(start 0.299974 0.150114)
			(end -0.299974 0.150114)
			(stroke
				(width 0.1)
				(type default)
			)
			(layer "F.Fab")
		)
		(fp_line
			(start -0.299974 -0.150114)
			(end 0.299974 -0.150114)
			(stroke
				(width 0.1)
				(type default)
			)
			(layer "F.Fab")
		)
		(fp_line
			(start 0.299974 -0.150114)
			(end 0.299974 0.150114)
			(stroke
				(width 0.1)
				(type default)
			)
			(layer "F.Fab")
		)
		(pad "1" smd rect
			(at -0.2667 0 270)
			(size 0.3048 0.381)
			(layers "F.Cu" "F.Mask" "F.Paste")
			(net "P5E_CPU1_P1_TX_C_DP<3>")
		)
		(pad "2" smd rect
			(at 0.2667 0 270)
			(size 0.3048 0.381)
			(layers "F.Cu" "F.Mask" "F.Paste")
			(net "P5E_CPU1_P1_TX_DP<3>")
		)
	)
	(footprint ""
		(layer "F.Cu")
		(at 66.715132 -331.99578 180)
		(property "Reference" "PC206"
			(at 0 0 180)
			(layer "F.SilkS")
			(hide yes)
			(effects
				(font
					(size 1.27 1.27)
				)
			)
		)
		(property "Value" ""
			(at 0 0 180)
			(layer "F.Fab")
			(effects
				(font
					(size 1.27 1.27)
				)
			)
		)
		(duplicate_pad_numbers_are_jumpers no)
		(fp_line
			(start 0.7874 0.4064)
			(end -0.7874 0.4064)
			(stroke
				(width 0.1524)
				(type default)
			)
			(layer "F.SilkS")
		)
		(fp_line
			(start 0.7874 -0.4064)
			(end 0.7874 0.4064)
			(stroke
				(width 0.1524)
				(type default)
			)
			(layer "F.SilkS")
		)
		(fp_line
			(start -0.7874 0.4064)
			(end -0.7874 -0.4064)
			(stroke
				(width 0.1524)
				(type default)
			)
			(layer "F.SilkS")
		)
		(fp_line
			(start -0.7874 -0.4064)
			(end 0.7874 -0.4064)
			(stroke
				(width 0.1524)
				(type default)
			)
			(layer "F.SilkS")
		)
		(fp_line
			(start 0.67945 0.3048)
			(end 0.120396 0.3048)
			(stroke
				(width 0.1)
				(type default)
			)
			(layer "F.Fab")
		)
		(fp_line
			(start 0.67945 -0.3048)
			(end 0.67945 0.3048)
			(stroke
				(width 0.1)
				(type default)
			)
			(layer "F.Fab")
		)
		(fp_line
			(start 0.12065 -0.2794)
			(end 0.12065 -0.3048)
			(stroke
				(width 0.1)
				(type default)
			)
			(layer "F.Fab")
		)
		(fp_line
			(start 0.12065 -0.3048)
			(end 0.67945 -0.3048)
			(stroke
				(width 0.1)
				(type default)
			)
			(layer "F.Fab")
		)
		(fp_line
			(start 0.120396 0.3048)
			(end 0.120396 0.2794)
			(stroke
				(width 0.1)
				(type default)
			)
			(layer "F.Fab")
		)
		(fp_line
			(start 0.120396 0.2794)
			(end -0.12065 0.2794)
			(stroke
				(width 0.1)
				(type default)
			)
			(layer "F.Fab")
		)
		(fp_line
			(start -0.12065 0.3048)
			(end -0.67945 0.3048)
			(stroke
				(width 0.1)
				(type default)
			)
			(layer "F.Fab")
		)
		(fp_line
			(start -0.12065 0.2794)
			(end -0.12065 0.3048)
			(stroke
				(width 0.1)
				(type default)
			)
			(layer "F.Fab")
		)
		(fp_line
			(start -0.12065 -0.2794)
			(end 0.12065 -0.2794)
			(stroke
				(width 0.1)
				(type default)
			)
			(layer "F.Fab")
		)
		(fp_line
			(start -0.12065 -0.305054)
			(end -0.12065 -0.2794)
			(stroke
				(width 0.1)
				(type default)
			)
			(layer "F.Fab")
		)
		(fp_line
			(start -0.67945 0.3048)
			(end -0.67945 -0.305054)
			(stroke
				(width 0.1)
				(type default)
			)
			(layer "F.Fab")
		)
		(fp_line
			(start -0.67945 -0.305054)
			(end -0.12065 -0.305054)
			(stroke
				(width 0.1)
				(type default)
			)
			(layer "F.Fab")
		)
		(pad "1" smd circle
			(at -0.40005 0 180)
			(size 0 0)
			(layers "F.Cu" "F.Mask" "F.Paste")
			(net "SW_PVDDCR_CPU1_P1_SW3")
		)
		(pad "2" smd circle
			(at 0.40005 0 180)
			(size 0 0)
			(layers "F.Cu" "F.Mask" "F.Paste")
			(net "SW_PVDDCR_CPU1_P1_SW3_RC")
		)
	)
)
